(kicad_pcb
	(version 20241229)
	(generator "pcbnew")
	(generator_version "9.0")
	(general
		(thickness 1.6)
		(legacy_teardrops no)
	)
	(paper "A4")
	(title_block
		(title "GMSL Deserializer")
		(date "2025-10-09")
		(rev "1.0.4")
		(company "Antmicro Ltd")
		(comment 1 "www.antmicro.com")
		(comment 9 "footprints 73-78 of 235")
	)
	(layers
		(0 "F.Cu" signal)
		(4 "In1.Cu" power)
		(6 "In2.Cu" power)
		(2 "B.Cu" signal)
		(9 "F.Adhes" user "F.Adhesive")
		(11 "B.Adhes" user "B.Adhesive")
		(13 "F.Paste" user)
		(15 "B.Paste" user)
		(5 "F.SilkS" user "F.Silkscreen")
		(7 "B.SilkS" user "B.Silkscreen")
		(1 "F.Mask" user)
		(3 "B.Mask" user)
		(17 "Dwgs.User" user "User.Drawings")
		(19 "Cmts.User" user "User.Comments")
		(21 "Eco1.User" user "User.Eco1")
		(23 "Eco2.User" user "User.Eco2")
		(25 "Edge.Cuts" user)
		(27 "Margin" user)
		(31 "F.CrtYd" user "F.Courtyard")
		(29 "B.CrtYd" user "B.Courtyard")
		(35 "F.Fab" user)
		(33 "B.Fab" user)
	)
	(footprint "antmicro-footprints:R_0603_1608Metric"
		(layer "F.Cu")
		(at 126.674 88.242 -90)
		(descr "Resistor SMD 0603")
		(tags "resistor SMD 0603")
		(property "Reference" "R41"
			(at -1.016 -1.524 90)
			(layer "F.SilkS")
			(effects
				(font
					(size 0.7 0.7)
					(thickness 0.15)
				)
				(justify right bottom)
			)
		)
		(property "Value" "R_0R_22.4A_0603"
			(at 0 1.6 90)
			(layer "F.Fab")
			(effects
				(font
					(size 0.7 0.7)
					(thickness 0.15)
				)
				(justify right bottom)
			)
		)
		(property "Datasheet" "https://fscdn.rohm.com/en/products/databook/datasheet/passive/resistor/chip_resistor/pmr-jpw-e.pdf"
			(at 0 0 270)
			(layer "F.Fab")
			(hide yes)
			(effects
				(font
					(size 1.27 1.27)
					(thickness 0.15)
				)
			)
		)
		(property "Description" "SMD Chip Resistor"
			(at 0 0 270)
			(layer "F.Fab")
			(hide yes)
			(effects
				(font
					(size 1.27 1.27)
					(thickness 0.15)
				)
			)
		)
		(property "Author" "Antmicro"
			(at 38.432 214.916 0)
			(layer "F.Fab")
			(hide yes)
			(effects
				(font
					(size 1 1)
					(thickness 0.15)
				)
			)
		)
		(property "License" "Apache-2.0"
			(at 38.432 214.916 0)
			(layer "F.Fab")
			(hide yes)
			(effects
				(font
					(size 1 1)
					(thickness 0.15)
				)
			)
		)
		(property "MPN" "PMR03EZPJ000"
			(at 38.432 214.916 0)
			(layer "F.Fab")
			(hide yes)
			(effects
				(font
					(size 1 1)
					(thickness 0.15)
				)
			)
		)
		(property "Manufacturer" "ROHM Semiconductor"
			(at 38.432 214.916 0)
			(layer "F.Fab")
			(hide yes)
			(effects
				(font
					(size 1 1)
					(thickness 0.15)
				)
			)
		)
		(property "Max. Curr." "22.4A"
			(at 38.432 214.916 0)
			(layer "F.Fab")
			(hide yes)
			(effects
				(font
					(size 1 1)
					(thickness 0.15)
				)
			)
		)
		(property "Tolerance" "template_tolerance"
			(at 38.432 214.916 0)
			(layer "F.Fab")
			(hide yes)
			(effects
				(font
					(size 1 1)
					(thickness 0.15)
				)
			)
		)
		(property "Val" "0R"
			(at 38.432 214.916 0)
			(layer "F.Fab")
			(hide yes)
			(effects
				(font
					(size 1 1)
					(thickness 0.15)
				)
			)
		)
		(sheetname "/Power/")
		(sheetfile "power.kicad_sch")
		(attr smd)
		(fp_line
			(start -0.15 0.4)
			(end 0.15 0.4)
			(stroke
				(width 0.15)
				(type solid)
			)
			(layer "F.SilkS")
		)
		(fp_line
			(start -0.15 -0.4)
			(end 0.15 -0.4)
			(stroke
				(width 0.15)
				(type solid)
			)
			(layer "F.SilkS")
		)
		(fp_rect
			(start -1.25 -0.65)
			(end 1.25 0.65)
			(stroke
				(width 0.05)
				(type solid)
			)
			(fill no)
			(layer "F.CrtYd")
		)
		(fp_rect
			(start -0.8 -0.4)
			(end 0.8 0.4)
			(stroke
				(width 0.15)
				(type solid)
			)
			(fill no)
			(layer "F.Fab")
		)
		(pad "1" smd roundrect
			(at -0.7 0 270)
			(size 0.8 1)
			(layers "F.Cu" "F.Mask" "F.Paste")
			(roundrect_rratio 0.2)
			(net 11 "/Power/OUT_1V2")
			(pintype "passive")
		)
		(pad "2" smd roundrect
			(at 0.7 0 270)
			(size 0.8 1)
			(layers "F.Cu" "F.Mask" "F.Paste")
			(roundrect_rratio 0.2)
			(net 73 "+1V2")
			(pintype "passive")
		)
	)
	(footprint "antmicro-footprints:R_0402_1005Metric"
		(layer "F.Cu")
		(at 179.837 68.834 -90)
		(descr "Resistor SMD 0402")
		(tags "resistor SMD 0402")
		(property "Reference" "R8"
			(at 8.1078 -0.249 90)
			(layer "F.SilkS")
			(effects
				(font
					(size 0.7 0.7)
					(thickness 0.15)
				)
				(justify right bottom)
			)
		)
		(property "Value" "R_200R_0402"
			(at -1.011843 1.772047 90)
			(layer "F.Fab")
			(effects
				(font
					(size 0.7 0.7)
					(thickness 0.15)
				)
				(justify right bottom)
			)
		)
		(property "Datasheet" "https://www.bourns.com/docs/product-datasheets/cr.pdf"
			(at 0 0 270)
			(layer "F.Fab")
			(hide yes)
			(effects
				(font
					(size 1.27 1.27)
					(thickness 0.15)
				)
			)
		)
		(property "Description" "SMD Chip Resistor, 200 ohm, ± 1%, 62.5 mW, 0402 [1005 Metric], Thick Film, General Purpose"
			(at 0 0 270)
			(layer "F.Fab")
			(hide yes)
			(effects
				(font
					(size 1.27 1.27)
					(thickness 0.15)
				)
			)
		)
		(property "Author" "Antmicro"
			(at 111.003 248.671 0)
			(layer "F.Fab")
			(hide yes)
			(effects
				(font
					(size 1 1)
					(thickness 0.15)
				)
			)
		)
		(property "License" "Apache-2.0"
			(at 111.003 248.671 0)
			(layer "F.Fab")
			(hide yes)
			(effects
				(font
					(size 1 1)
					(thickness 0.15)
				)
			)
		)
		(property "MPN" "CR0402-FX-2000GLF"
			(at 111.003 248.671 0)
			(layer "F.Fab")
			(hide yes)
			(effects
				(font
					(size 1 1)
					(thickness 0.15)
				)
			)
		)
		(property "Manufacturer" "Bourns"
			(at 111.003 248.671 0)
			(layer "F.Fab")
			(hide yes)
			(effects
				(font
					(size 1 1)
					(thickness 0.15)
				)
			)
		)
		(property "Tolerance" "1%"
			(at 111.003 248.671 0)
			(layer "F.Fab")
			(hide yes)
			(effects
				(font
					(size 1 1)
					(thickness 0.15)
				)
			)
		)
		(property "Val" "200R"
			(at 111.003 248.671 0)
			(layer "F.Fab")
			(hide yes)
			(effects
				(font
					(size 1 1)
					(thickness 0.15)
				)
			)
		)
		(sheetname "/Connectors/")
		(sheetfile "connectors.kicad_sch")
		(attr smd exclude_from_pos_files exclude_from_bom dnp)
		(fp_rect
			(start -0.925 -0.47)
			(end 0.925 0.47)
			(stroke
				(width 0.05)
				(type default)
			)
			(fill no)
			(layer "F.CrtYd")
		)
		(fp_rect
			(start -0.5 -0.25)
			(end 0.5 0.25)
			(stroke
				(width 0.15)
				(type solid)
			)
			(fill no)
			(layer "F.Fab")
		)
		(pad "1" smd roundrect
			(at -0.48 0 270)
			(size 0.59 0.64)
			(layers "F.Cu" "F.Mask" "F.Paste")
			(roundrect_rratio 0.25)
			(net 66 "/Connectors/VSYNC_CAM1")
			(pintype "passive")
		)
		(pad "2" smd roundrect
			(at 0.48 0 270)
			(size 0.59 0.64)
			(layers "F.Cu" "F.Mask" "F.Paste")
			(roundrect_rratio 0.25)
			(net 67 "/Connectors/VSYNC_CAM0")
			(pintype "passive")
		)
	)
	(footprint "antmicro-footprints:L_Coilcraft-1210POC"
		(layer "F.Cu")
		(at 148.336 56.642 90)
		(property "Reference" "L7"
			(at -0.635 -1.7 90)
			(layer "F.SilkS")
			(effects
				(font
					(size 0.7 0.7)
					(thickness 0.15)
				)
				(justify left bottom)
			)
		)
		(property "Value" "L_6u8_1A_Coilcraft-1210POC"
			(at 0 2.4 90)
			(layer "F.Fab")
			(effects
				(font
					(size 0.7 0.7)
					(thickness 0.15)
				)
				(justify left bottom)
			)
		)
		(property "Datasheet" "https://www.coilcraft.com/getmedia/5e8de018-68c5-4442-84ce-d5212c44660c/1210poc.pdf"
			(at 0 0 90)
			(layer "F.Fab")
			(hide yes)
			(effects
				(font
					(size 1.27 1.27)
					(thickness 0.15)
				)
			)
		)
		(property "Description" "Power Inductor (SMT), 6.8 µH, 9.2 A, Shielded, 12.8 A, XAL7070"
			(at 0 0 90)
			(layer "F.Fab")
			(hide yes)
			(effects
				(font
					(size 1.27 1.27)
					(thickness 0.15)
				)
			)
		)
		(property "Author" "Antmicro"
			(at 204.978 -91.694 0)
			(layer "F.Fab")
			(hide yes)
			(effects
				(font
					(size 1 1)
					(thickness 0.15)
				)
			)
		)
		(property "IMax" "1.36 A"
			(at 204.978 -91.694 0)
			(layer "F.Fab")
			(hide yes)
			(effects
				(font
					(size 1 1)
					(thickness 0.15)
				)
			)
		)
		(property "ISat" "1 A"
			(at 204.978 -91.694 0)
			(layer "F.Fab")
			(hide yes)
			(effects
				(font
					(size 1 1)
					(thickness 0.15)
				)
			)
		)
		(property "License" "Apache-2.0"
			(at 204.978 -91.694 0)
			(layer "F.Fab")
			(hide yes)
			(effects
				(font
					(size 1 1)
					(thickness 0.15)
				)
			)
		)
		(property "MPN" "1210POC-682"
			(at 204.978 -91.694 0)
			(layer "F.Fab")
			(hide yes)
			(effects
				(font
					(size 1 1)
					(thickness 0.15)
				)
			)
		)
		(property "Manufacturer" "Coilcraft"
			(at 204.978 -91.694 0)
			(layer "F.Fab")
			(hide yes)
			(effects
				(font
					(size 1 1)
					(thickness 0.15)
				)
			)
		)
		(property "Size" "2.67x3.3"
			(at 204.978 -91.694 0)
			(layer "F.Fab")
			(hide yes)
			(effects
				(font
					(size 1 1)
					(thickness 0.15)
				)
			)
		)
		(property "Val" "6u8/1A"
			(at 204.978 -91.694 0)
			(layer "F.Fab")
			(hide yes)
			(effects
				(font
					(size 1 1)
					(thickness 0.15)
				)
			)
		)
		(sheetname "/Power/")
		(sheetfile "power.kicad_sch")
		(attr smd)
		(fp_line
			(start -0.7 -1.4)
			(end 0.7 -1.4)
			(stroke
				(width 0.15)
				(type solid)
			)
			(layer "F.SilkS")
		)
		(fp_line
			(start -0.7 1.4)
			(end 0.7 1.4)
			(stroke
				(width 0.15)
				(type solid)
			)
			(layer "F.SilkS")
		)
		(fp_rect
			(start -1.9 -1.585)
			(end 1.9 1.585)
			(stroke
				(width 0.05)
				(type solid)
			)
			(fill no)
			(layer "F.CrtYd")
		)
		(fp_line
			(start 1.65 -1.335)
			(end -1.65 -1.335)
			(stroke
				(width 0.15)
				(type solid)
			)
			(layer "F.Fab")
		)
		(fp_line
			(start 1.65 1.335)
			(end 1.65 -1.335)
			(stroke
				(width 0.15)
				(type solid)
			)
			(layer "F.Fab")
		)
		(fp_line
			(start 1.65 1.335)
			(end -1.65 1.335)
			(stroke
				(width 0.15)
				(type solid)
			)
			(layer "F.Fab")
		)
		(fp_line
			(start -1.65 1.335)
			(end -1.65 -1.335)
			(stroke
				(width 0.15)
				(type solid)
			)
			(layer "F.Fab")
		)
		(pad "1" smd rect
			(at -1.27 0 90)
			(size 0.65 2.65)
			(layers "F.Cu" "F.Mask" "F.Paste")
			(net 53 "Net-(L3-Pad2)")
			(pintype "passive")
		)
		(pad "2" smd rect
			(at 1.27 0 90)
			(size 0.65 2.65)
			(layers "F.Cu" "F.Mask" "F.Paste")
			(net 57 "Net-(L11-Pad1)")
			(pintype "passive")
		)
	)
	(footprint "antmicro-footprints:TP_SMD_0.75mm"
		(layer "F.Cu")
		(at 142.748 97.78)
		(property "Reference" "TP15"
			(at 0 -0.6 0)
			(layer "F.SilkS")
			(hide yes)
			(effects
				(font
					(size 0.7 0.7)
					(thickness 0.15)
				)
				(justify left bottom)
			)
		)
		(property "Value" "TP_0.75mm_SMD"
			(at 0 1.2 0)
			(layer "F.Fab")
			(effects
				(font
					(size 0.7 0.7)
					(thickness 0.15)
				)
				(justify left bottom)
			)
		)
		(property "Description" "SMT test point"
			(at 0 0 0)
			(layer "F.Fab")
			(hide yes)
			(effects
				(font
					(size 1.27 1.27)
					(thickness 0.15)
				)
			)
		)
		(property "Author" "Antmicro"
			(at 0 0 0)
			(layer "F.Fab")
			(hide yes)
			(effects
				(font
					(size 1 1)
					(thickness 0.15)
				)
			)
		)
		(property "License" "Apache-2.0"
			(at 0 0 0)
			(layer "F.Fab")
			(hide yes)
			(effects
				(font
					(size 1 1)
					(thickness 0.15)
				)
			)
		)
		(property "MPN" ""
			(at 0 0 0)
			(layer "F.Fab")
			(hide yes)
			(effects
				(font
					(size 1 1)
					(thickness 0.15)
				)
			)
		)
		(property "Manufacturer" ""
			(at 0 0 0)
			(layer "F.Fab")
			(hide yes)
			(effects
				(font
					(size 1 1)
					(thickness 0.15)
				)
			)
		)
		(sheetname "/Power/")
		(sheetfile "power.kicad_sch")
		(fp_circle
			(center 0 0)
			(end 0.475 0)
			(stroke
				(width 0.05)
				(type default)
			)
			(fill no)
			(layer "F.CrtYd")
		)
		(pad "1" smd circle
			(at 0 0)
			(size 0.75 0.75)
			(layers "F.Cu" "F.Mask")
			(net 1 "GND")
			(pinfunction "1")
			(pintype "passive")
		)
	)
	(footprint "antmicro-footprints:SOD-523_NP"
		(layer "F.Cu")
		(at 178.054 67.31 -90)
		(property "Reference" "D7"
			(at -0.85 0.607653 90)
			(layer "F.SilkS")
			(effects
				(font
					(size 0.7 0.7)
					(thickness 0.15)
				)
				(justify right bottom)
			)
		)
		(property "Value" "ESD5B5_0ST1G"
			(at 0 1.499 90)
			(layer "F.Fab")
			(effects
				(font
					(size 0.7 0.7)
					(thickness 0.15)
				)
				(justify right bottom)
			)
		)
		(property "Datasheet" "https://www.onsemi.com/pdf/datasheet/esd5b5.0st1-d.pdf"
			(at 0 0 270)
			(layer "F.Fab")
			(hide yes)
			(effects
				(font
					(size 1.27 1.27)
					(thickness 0.15)
				)
			)
		)
		(property "Description" "Bidirectional TVS, 30 kV,  SOD-523, 5 V, 32 pF"
			(at 0 0 270)
			(layer "F.Fab")
			(hide yes)
			(effects
				(font
					(size 1.27 1.27)
					(thickness 0.15)
				)
			)
		)
		(property "Author" "Antmicro"
			(at 110.744 245.364 0)
			(layer "F.Fab")
			(hide yes)
			(effects
				(font
					(size 1 1)
					(thickness 0.15)
				)
			)
		)
		(property "License" "Apache-2.0"
			(at 110.744 245.364 0)
			(layer "F.Fab")
			(hide yes)
			(effects
				(font
					(size 1 1)
					(thickness 0.15)
				)
			)
		)
		(property "MPN" "ESD5B5.0ST1G"
			(at 110.744 245.364 0)
			(layer "F.Fab")
			(hide yes)
			(effects
				(font
					(size 1 1)
					(thickness 0.15)
				)
			)
		)
		(property "Manufacturer" "ON Semiconductor"
			(at 110.744 245.364 0)
			(layer "F.Fab")
			(hide yes)
			(effects
				(font
					(size 1 1)
					(thickness 0.15)
				)
			)
		)
		(sheetname "/Connectors/")
		(sheetfile "connectors.kicad_sch")
		(attr smd)
		(fp_rect
			(start -1 -0.6)
			(end 1 0.6)
			(stroke
				(width 0.05)
				(type solid)
			)
			(fill no)
			(layer "F.CrtYd")
		)
		(fp_line
			(start -0.652 0.423)
			(end 0.65 0.423)
			(stroke
				(width 0.15)
				(type solid)
			)
			(layer "F.Fab")
		)
		(fp_line
			(start -0.652 0.423)
			(end -0.652 -0.425)
			(stroke
				(width 0.15)
				(type solid)
			)
			(layer "F.Fab")
		)
		(fp_line
			(start -0.652 -0.425)
			(end 0.65 -0.425)
			(stroke
				(width 0.15)
				(type solid)
			)
			(layer "F.Fab")
		)
		(fp_line
			(start 0.65 -0.425)
			(end 0.65 0.423)
			(stroke
				(width 0.15)
				(type solid)
			)
			(layer "F.Fab")
		)
		(pad "1" smd roundrect
			(at -0.701 0 270)
			(size 0.5 0.6)
			(layers "F.Cu" "F.Mask" "F.Paste")
			(roundrect_rratio 0.25)
			(net 1 "GND")
			(pinfunction "C")
			(pintype "passive")
		)
		(pad "2" smd roundrect
			(at 0.699 0 270)
			(size 0.5 0.6)
			(layers "F.Cu" "F.Mask" "F.Paste")
			(roundrect_rratio 0.25)
			(net 66 "/Connectors/VSYNC_CAM1")
			(pinfunction "A")
			(pintype "passive")
		)
	)
	(footprint "antmicro-footprints:C_0402_1005Metric"
		(layer "F.Cu")
		(at 182.132 60.1975 -90)
		(descr "Capacitor SMD 0402")
		(tags "capacitor SMD 0402")
		(property "Reference" "C5"
			(at -0.7615 0.522 90)
			(layer "F.SilkS")
			(effects
				(font
					(size 0.7 0.7)
					(thickness 0.15)
				)
				(justify right bottom)
			)
		)
		(property "Value" "C_1u_0402"
			(at -1.022927 2.155213 90)
			(layer "F.Fab")
			(effects
				(font
					(size 0.7 0.7)
					(thickness 0.15)
				)
				(justify right bottom)
			)
		)
		(property "Datasheet" "https://product.tdk.com/en/search/capacitor/ceramic/mlcc/info?part_no=C1005X6S1A105K050BC"
			(at 0 0 270)
			(layer "F.Fab")
			(hide yes)
			(effects
				(font
					(size 1.27 1.27)
					(thickness 0.15)
				)
			)
		)
		(property "Description" "SMD Multilayer Ceramic Capacitor, 1 µF, 10 V, 0402 [1005 Metric], ± 10%, X6S, C"
			(at 0 0 270)
			(layer "F.Fab")
			(hide yes)
			(effects
				(font
					(size 1.27 1.27)
					(thickness 0.15)
				)
			)
		)
		(property "Author" "Antmicro"
			(at 121.9345 242.3295 0)
			(layer "F.Fab")
			(hide yes)
			(effects
				(font
					(size 1 1)
					(thickness 0.15)
				)
			)
		)
		(property "Dielectric" ""
			(at 121.9345 242.3295 0)
			(layer "F.Fab")
			(hide yes)
			(effects
				(font
					(size 1 1)
					(thickness 0.15)
				)
			)
		)
		(property "License" "Apache-2.0"
			(at 121.9345 242.3295 0)
			(layer "F.Fab")
			(hide yes)
			(effects
				(font
					(size 1 1)
					(thickness 0.15)
				)
			)
		)
		(property "MPN" "C1005X6S1A105K050BC"
			(at 121.9345 242.3295 0)
			(layer "F.Fab")
			(hide yes)
			(effects
				(font
					(size 1 1)
					(thickness 0.15)
				)
			)
		)
		(property "Manufacturer" "TDK"
			(at 121.9345 242.3295 0)
			(layer "F.Fab")
			(hide yes)
			(effects
				(font
					(size 1 1)
					(thickness 0.15)
				)
			)
		)
		(property "Val" "1u"
			(at 121.9345 242.3295 0)
			(layer "F.Fab")
			(hide yes)
			(effects
				(font
					(size 1 1)
					(thickness 0.15)
				)
			)
		)
		(property "Voltage" ""
			(at 121.9345 242.3295 0)
			(layer "F.Fab")
			(hide yes)
			(effects
				(font
					(size 1 1)
					(thickness 0.15)
				)
			)
		)
		(sheetname "/Connectors/")
		(sheetfile "connectors.kicad_sch")
		(attr smd)
		(fp_rect
			(start -0.925 -0.47)
			(end 0.925 0.47)
			(stroke
				(width 0.05)
				(type default)
			)
			(fill no)
			(layer "F.CrtYd")
		)
		(fp_line
			(start -0.494 0.248)
			(end -0.494 -0.25)
			(stroke
				(width 0.15)
				(type solid)
			)
			(layer "F.Fab")
		)
		(fp_line
			(start 0.504 0.248)
			(end -0.494 0.248)
			(stroke
				(width 0.15)
				(type solid)
			)
			(layer "F.Fab")
		)
		(fp_line
			(start -0.494 -0.25)
			(end 0.504 -0.25)
			(stroke
				(width 0.15)
				(type solid)
			)
			(layer "F.Fab")
		)
		(fp_line
			(start 0.504 -0.25)
			(end 0.504 0.248)
			(stroke
				(width 0.15)
				(type solid)
			)
			(layer "F.Fab")
		)
		(pad "1" smd roundrect
			(at -0.48 0 270)
			(size 0.59 0.64)
			(layers "F.Cu" "F.Mask" "F.Paste")
			(roundrect_rratio 0.25)
			(net 1 "GND")
			(pintype "passive")
		)
		(pad "2" smd roundrect
			(at 0.48 0 270)
			(size 0.59 0.64)
			(layers "F.Cu" "F.Mask" "F.Paste")
			(roundrect_rratio 0.25)
			(net 113 "/Connectors/FFC_5V")
			(pintype "passive")
		)
	)
)
